(kicad_pcb
	(version 20260206)
	(generator "pcbnew")
	(generator_version "10.0")
	(general
		(thickness 1.6)
		(legacy_teardrops no)
	)
	(paper "A4")
	(title_block
		(title "v1-pdb — T6M_PDB_D_0927_0900.brd")
		(comment 1 "Open CloudServer (Microsoft) / footprints 319-319 of 321")
	)
	(layers
		(0 "F.Cu" signal "TOP")
		(4 "In1.Cu" signal "GND")
		(6 "In2.Cu" signal "IN1")
		(8 "In3.Cu" signal "VCC")
		(10 "In4.Cu" signal "VCC1")
		(12 "In5.Cu" signal "IN2")
		(14 "In6.Cu" signal "GND1")
		(2 "B.Cu" signal "BOTTOM")
		(9 "F.Adhes" user "F.Adhesive")
		(11 "B.Adhes" user "B.Adhesive")
		(13 "F.Paste" user "Package Geometry/Pastemask Top")
		(15 "B.Paste" user "Package Geometry/Pastemask Bottom")
		(5 "F.SilkS" user "Ref Des/Silkscreen Top")
		(7 "B.SilkS" user "Ref Des/Silkscreen Bottom")
		(1 "F.Mask" user "Board Geometry/Soldermask Top")
		(3 "B.Mask" user "Board Geometry/Soldermask Bottom")
		(17 "Dwgs.User" user "User.Drawings")
		(19 "Cmts.User" user "User.Comments")
		(21 "Eco1.User" user "User.Eco1")
		(23 "Eco2.User" user "User.Eco2")
		(25 "Edge.Cuts" user "Board Geometry/Outline")
		(27 "Margin" user)
		(31 "F.CrtYd" user "Package Geometry/Place Bound Top")
		(29 "B.CrtYd" user "Package Geometry/Place Bound Bottom")
		(35 "F.Fab" user "Ref Des/Assembly Top")
		(33 "B.Fab" user "Ref Des/Assembly Bottom")
	)
	(footprint ""
		(layer "B.Cu")
		(at 14.010132 -224.098358)
		(property "Reference" ""
			(at 0 0 0)
			(layer "B.SilkS")
			(hide yes)
			(effects
				(font
					(size 1.27 1.27)
				)
				(justify mirror)
			)
		)
		(property "Value" ""
			(at 0 0 0)
			(layer "B.Fab")
			(effects
				(font
					(size 1.27 1.27)
				)
				(justify mirror)
			)
		)
		(duplicate_pad_numbers_are_jumpers no)
		(fp_poly
			(pts
				(arc
					(start 1.4986 0)
					(mid -1.4986 0)
					(end 1.4986 0)
				)
			)
			(stroke
				(width 0)
				(type default)
			)
			(fill no)
			(layer "B.CrtYd")
		)
		(pad "1" smd circle
			(at 0 0 180)
			(size 0.9906 0.9906)
			(layers "B.Cu" "B.Mask" "B.Paste")
			(net "Net_3")
		)
		(zone
			(layer "B.Cu")
			(hatch none 0.5)
			(connect_pads
				(clearance 0)
			)
			(min_thickness 0.25)
			(keepout
				(tracks not_allowed)
				(vias allowed)
				(pads allowed)
				(copperpour not_allowed)
				(footprints allowed)
			)
			(placement
				(enabled no)
				(sheetname "")
			)
			(fill
				(thermal_gap 0.5)
				(thermal_bridge_width 0.5)
				(island_removal_mode 0)
			)
			(polygon
				(pts
					(arc
						(start 15.635732 -224.098358)
						(mid 12.384532 -224.098358)
						(end 15.635732 -224.098358)
					)
				)
			)
		)
	)
)
